FILE_TYPE = MULTI_PHYS_TABLE;

PART 'SCHOTTKY_AC'

{========================================================================================}
:VALUE             | PART_TYPE | MATERIAL | PART_NUMBER    = STANDARD        | LIFECYCLE      | PART_NUMBER   | JEDEC_TYPE                 | DESCRIPTION                                | MANUFTR | MANUF_PN          | RD_CMPLS_LVL | CMPLS_LVL | CLASS | DIP_SMD | FP_ECN            | FROM_PJ          | DATA                                  | EE_CHECK_LIST | PSL | PREFERENCE | CREATOR | CREATEDAY  | STATUS ;
{========================================================================================}
 '60V/51.70A'      | 'SMLF'    | 'IC'     | 'BC0MDJ60Z00'(!) = ''              | ''             | 'BC0MDJ60Z00' |'D2723_SMCXC'| 'DIODE SMD 5.0SMDJ60A(60V,51.70A)'         | 'LFI'   | '5.0SMDJ60A'      | 'EP(V1)'     | 'EP(V1)'  | 'IC'  | ''      | ''                | 'T2L-CHEESE'     | '5-0SMD SERIES.pdf'                   | ''            | ''  | ''         | ''      | '20120131' | ''    
 '60V/51.70A'      | 'SMLF'    | 'EMPTY'  | 'BC0MDJ60Z00'(!) = ''              | ''             | 'BC0MDJ60Z00' |'D2723_SMCXC'| 'DIODE SMD 5.0SMDJ60A(60V,51.70A)'         | 'LFI'   | '5.0SMDJ60A'      | 'EP(V1)'     | 'EP(V1)'  | 'IC'  | ''      | ''                | 'T2L-CHEESE'     | '5-0SMD SERIES.pdf'                   | ''            | ''  | ''         | ''      | '20120131' | ''    
 'B380-13-F'       | 'SMLF'    | 'IC'     | 'BC00B380Z00'(!) = ''              | ''             | 'BC00B380Z00' |'D2723_SMCXD'| 'DIODE SMD B380-13-F(80V,100A,SCHOTTKY)'   | 'DDS'   | 'B380-13-F'       | 'EP(V1)'     | ''        | 'IC'  | ''      | ''                | 'T2L-CHEESE'     | 'DDS_B380B.pdf'                       | ''            | ''  | ''         | ''      | '20120207' | ''    
 'B380-13-F'       | 'SMLF'    | 'EMPTY'  | 'BC00B380Z00'(!) = ''              | ''             | 'BC00B380Z00' |'D2723_SMCXD'| 'DIODE SMD B380-13-F(80V,100A,SCHOTTKY)'   | 'DDS'   | 'B380-13-F'       | 'EP(V1)'     | ''        | 'IC'  | ''      | ''                | 'T2L-CHEESE'     | 'DDS_B380B.pdf'                       | ''            | ''  | ''         | ''      | '20120207' | ''    
 'MMSZ5230B'       | 'SMLF'    | 'IC'     | 'BD005230Z00'(!) = ''              | ''             | 'BD005230Z00' |'SOD123XD'| 'DIOIDE ZENER SMD MMSZ5230B(4.7V,SOD123)'  | 'PJT'   | 'MMSZ5230B'       | 'EU(V1)'     | ''        | 'IC'  | ''      | ''                | 'T2L-KC'         | 'MMSZ5245B-series.pdf'                | ''            | ''  | ''         | ''      | '20120329' | ''    
 'MMSZ5230B'       | 'SMLF'    | 'EMPTY'  | 'BD005230Z00'(!) = ''              | ''             | 'BD005230Z00' |'SOD123XD'| 'DIOIDE ZENER SMD MMSZ5230B(4.7V,SOD123)'  | 'PJT'   | 'MMSZ5230B'       | 'EU(V1)'     | ''        | 'IC'  | ''      | ''                | 'T2L-KC'         | 'MMSZ5245B-series.pdf'                | ''            | ''  | ''         | ''      | '20120329' | ''    
 'VS-30BQ040TRPBF' | 'SMLF'    | 'IC'     | 'BC30BQ04Z00'(!) = 'End of Design' | 'End of Life'  | 'BC30BQ04Z00' |'D2723_SMCXE_EOL'| 'DIODE SMD VS-30BQ040TRPBF(40V,3A)SMC'     | 'SIL'   | 'VS-30BQ040TRPBF' | 'EU(V1)'     | 'EU(V1)'  | 'IC'  | ''      | ''                | 'S2B-YU-LIN'     | 'SIL_VS-30BQ040TRPBF.pdf'             | ''            | ''  | ''         | ''      | '20120904' | ''    
 'VS-30BQ040TRPBF' | 'SMLF'    | 'EMPTY'  | 'BC30BQ04Z00'(!) = 'End of Design' | 'End of Life'  | 'BC30BQ04Z00' |'D2723_SMCXE_EOL'| 'DIODE SMD VS-30BQ040TRPBF(40V,3A)SMC'     | 'SIL'   | 'VS-30BQ040TRPBF' | 'EU(V1)'     | 'EU(V1)'  | 'IC'  | ''      | ''                | 'S2B-YU-LIN'     | 'SIL_VS-30BQ040TRPBF.pdf'             | ''            | ''  | ''         | ''      | '20120904' | ''    
 'SS0530'          | 'SMLF'    | 'IC'     | 'BCSS0530Z00'(!) = ''              | ''             | 'BCSS0530Z00' |'SOD123XD'| 'DIODE SMD SS0530(30V,0.5A)SOD-123'        | 'PJT'   | 'SS0530'          | 'EP(V1)'     | ''        | 'IC'  | ''      | ''                | 'S1D-OZ'         | 'PJT_SS0520-SS0540.pdf'               | ''            | ''  | ''         | ''      | '20120915' | ''    
 'SS0530'          | 'SMLF'    | 'EMPTY'  | 'BCSS0530Z00'(!) = ''              | ''             | 'BCSS0530Z00' |'SOD123XD'| 'DIODE SMD SS0530(30V,0.5A)SOD-123'        | 'PJT'   | 'SS0530'          | 'EP(V1)'     | ''        | 'IC'  | ''      | ''                | 'S1D-OZ'         | 'PJT_SS0520-SS0540.pdf'               | ''            | ''  | ''         | ''      | '20120915' | ''    
 'MBR0530T1G'      | 'SMLF'    | 'IC'     | 'BC000530Z33'(!) = 'End of Design' | 'Comp-Approve' | 'BC000530Z33' |'SOD123XE'| 'DIODE SCHOTTKY MBR0530T1G(SOD-123)'       | 'ONS'   | 'MBR0530T1G'      | 'EU(V1)'     | 'EU(V1)'  | 'IC'  | ''      | ''                | 'F03B-MARK'      | 'ONS_MBR0530T1-MBR0530T3.pdf'         | ''            | ''  | ''         | ''      | '20121114' | ''    
 'MBR0530T1G'      | 'SMLF'    | 'EMPTY'  | 'BC000530Z33'(!) = 'End of Design' | 'Comp-Approve' | 'BC000530Z33' |'SOD123XE'| 'DIODE SCHOTTKY MBR0530T1G(SOD-123)'       | 'ONS'   | 'MBR0530T1G'      | 'EU(V1)'     | 'EU(V1)'  | 'IC'  | ''      | ''                | 'F03B-MARK'      | 'ONS_MBR0530T1-MBR0530T3.pdf'         | ''            | ''  | ''         | ''      | '20121114' | ''    
 '100V/0.2A'       | 'SMLF'    | 'IC'     | 'BCBAT41KZ00'(!) = 'End of Design' | 'Comp-Approve' | 'BCBAT41KZ00' |'SOD523XB'| 'DIODE SMD BAT41KFILM(100V,0.2A,SCHOTTKY)' | 'SGT'   | 'BAT41KFILM'      | 'EP(V1)'     | ''        | 'IC'  | ''      | ''                | 'UH3-JOSH'       | 'SGT_BAT41.pdf'                       | ''            | ''  | ''         | ''      | '20120531' | ''    
 '100V/0.2A'       | 'SMLF'    | 'EMPTY'  | 'BCBAT41KZ00'(!) = 'End of Design' | 'Comp-Approve' | 'BCBAT41KZ00' |'SOD523XB'| 'DIODE SMD BAT41KFILM(100V,0.2A,SCHOTTKY)' | 'SGT'   | 'BAT41KFILM'      | 'EP(V1)'     | ''        | 'IC'  | ''      | ''                | 'UH3-JOSH'       | 'SGT_BAT41.pdf'                       | ''            | ''  | ''         | ''      | '20120531' | ''    
 'SBM54'           | 'SMLF'    | 'IC'     | 'BC0SBM54Z13'(!) = 'End of Design' | 'End of Life'  | 'BC0SBM54Z13' |'D2114_EOL'| 'DIODE SMD SBM54PT(40V.5A)SCHOTTKY'        | 'CNK'   | 'SBM54PT'         | ''           | 'EP'      | 'IC'  | ''      | ''                | 'S07'            | 'CNK_SBM54PT.pdf'                     | ''            | ''  | ''         | ''      | '20100726' | ''    
 'SBM54'           | 'SMLF'    | 'EMPTY'  | 'BC0SBM54Z13'(!) = 'End of Design' | 'End of Life'  | 'BC0SBM54Z13' |'D2114_EOL'| 'DIODE SMD SBM54PT(40V.5A)SCHOTTKY'        | 'CNK'   | 'SBM54PT'         | ''           | 'EP'      | 'IC'  | ''      | ''                | 'S07'            | 'CNK_SBM54PT.pdf'                     | ''            | ''  | ''         | ''      | '20100726' | ''    
 'BAT54T1G'        | 'SMLF'    | 'IC'     | 'BCBAT54TZ03'(!) = ''              | ''             | 'BCBAT54TZ03' |'SOD123XE'| 'DIODE SMD BAT54T1G(30V,0.2A,SOD-123)'     | 'ONS'   | 'BAT54T1G'        | 'EP(V1)'     | ''        | 'IC'  | ''      | ''                | 'T2H-ALAN'       | 'ONS_BAT54T1G.pdf'                    | ''            | ''  | ''         | ''      | '20121203' | ''    
 'BAT54T1G'        | 'SMLF'    | 'EMPTY'  | 'BCBAT54TZ03'(!) = ''              | ''             | 'BCBAT54TZ03' |'SOD123XE'| 'DIODE SMD BAT54T1G(30V,0.2A,SOD-123)'     | 'ONS'   | 'BAT54T1G'        | 'EP(V1)'     | ''        | 'IC'  | ''      | ''                | 'T2H-ALAN'       | 'ONS_BAT54T1G.pdf'                    | ''            | ''  | ''         | ''      | '20121203' | ''    
 'MBRS130LT3G'     | 'SMLF'    | 'IC'     | 'BC000130ZD3'(!) = 'End of Design' | 'Comp-Approve' | 'BC000130ZD3' |'D2114'| 'DIODE SMD MBRS130LT3G(30V 1A SBD)'        | 'ONS'   | 'MBRS130LT3G'     | ''           | 'EU'      | 'IC'  | ''      | ''                | 'S75-LA'         | 'MBRS130LT3G.pdf'                     | ''            | ''  | ''         | ''      | '20130108' | ''    
 'MBRS130LT3G'     | 'SMLF'    | 'EMPTY'  | 'BC000130ZD3'(!) = 'End of Design' | 'Comp-Approve' | 'BC000130ZD3' |'D2114'| 'DIODE SMD MBRS130LT3G(30V 1A SBD)'        | 'ONS'   | 'MBRS130LT3G'     | ''           | 'EU'      | 'IC'  | ''      | ''                | 'S75-LA'         | 'MBRS130LT3G.pdf'                     | ''            | ''  | ''         | ''      | '20130108' | ''    
 'SMBJ13A-13-F'    | 'SMLF'    | 'IC'     | 'BC0MBJ13Z01'(!) = ''              | ''             | 'BC0MBJ13Z01' |'D2114A'| 'DIODE SMD SMBJ13A-13-F(13V, 27.9A)'       | 'DDS'   | 'SMBJ13A-13-F'    | 'EU(V1)'     | ''        | 'IC'  | ''      | ''                | 'S1MS-CHEESE'    | 'DDS_SMBJ5(C)A-SMBJ170(C)A.pdf'       | ''            | ''  | ''         | ''      | '20130319' | ''    
 'SMBJ13A-13-F'    | 'SMLF'    | 'EMPTY'  | 'BC0MBJ13Z01'(!) = ''              | ''             | 'BC0MBJ13Z01' |'D2114A'| 'DIODE SMD SMBJ13A-13-F(13V, 27.9A)'       | 'DDS'   | 'SMBJ13A-13-F'    | 'EU(V1)'     | ''        | 'IC'  | ''      | ''                | 'S1MS-CHEESE'    | 'DDS_SMBJ5(C)A-SMBJ170(C)A.pdf'       | ''            | ''  | ''         | ''      | '20130319' | ''    
 'SMBJ13A'         | 'SMLF'    | 'IC'     | 'BC0MBJ13Z00'(!) = ''              | ''             | 'BC0MBJ13Z00' |'D2114XB'| 'DIODE SMD SMBJ13A(13V,600W)DO-214AA'      | 'LFI'   | 'SMBJ13A'         | 'EP(V1)'     | 'EP(V1)'  | 'IC'  | ''      | ''                | 'JBF-MEALY'      | 'LFI_SMBJ-SERIES.pdf'                 | ''            | ''  | ''         | ''      | '20130403' | ''    
 'SMBJ13A'         | 'SMLF'    | 'EMPTY'  | 'BC0MBJ13Z00'(!) = ''              | ''             | 'BC0MBJ13Z00' |'D2114XB'| 'DIODE SMD SMBJ13A(13V,600W)DO-214AA'      | 'LFI'   | 'SMBJ13A'         | 'EP(V1)'     | 'EP(V1)'  | 'IC'  | ''      | ''                | 'JBF-MEALY'      | 'LFI_SMBJ-SERIES.pdf'                 | ''            | ''  | ''         | ''      | '20130403' | ''    
 'PMEG2005AEL'     | 'SMLF'    | 'IC'     | 'BC2005AEZ00'(!) = ''              | ''             | 'BC2005AEZ00' |'SOD882'| 'DIODE PMEG2005AEL(20V,0.5A)(SOD882)'      | 'NXP'   | 'PMEG2005AEL'     | 'EP(V1)'     | 'EP(V1)'  | 'IC'  | ''      | ''                | 'S2S-BENJAMIN'   | 'NXP_PMEG2005AEL.pdf'                 | ''            | ''  | ''         | ''      | '20130514' | ''    
 'PMEG2005AEL'     | 'SMLF'    | 'EMPTY'  | 'BC2005AEZ00'(!) = ''              | ''             | 'BC2005AEZ00' |'SOD882'| 'DIODE PMEG2005AEL(20V,0.5A)(SOD882)'      | 'NXP'   | 'PMEG2005AEL'     | 'EP(V1)'     | 'EP(V1)'  | 'IC'  | ''      | ''                | 'S2S-BENJAMIN'   | 'NXP_PMEG2005AEL.pdf'                 | ''            | ''  | ''         | ''      | '20130514' | ''    
 'SX33L'           | 'SMLF'    | 'IC'     | 'BC0SX33LZ00'(!) = ''              | ''             | 'BC0SX33LZ00' |'D2010XH'| 'DIODE SMD SX33L(30V,3A,SCHOTTKY,SMA)'     | 'PJT'   | 'SX33L'           | 'EU(V1)'     | 'EU(V1)'  | 'IC'  | ''      | ''                | 'S2MF-VINCENT'   | 'PJT_SX33L.pdf'                       | ''            | ''  | ''         | ''      | '20130719' | ''    
 'SX33L'           | 'SMLF'    | 'EMPTY'  | 'BC0SX33LZ00'(!) = ''              | ''             | 'BC0SX33LZ00' |'D2010XH'| 'DIODE SMD SX33L(30V,3A,SCHOTTKY,SMA)'     | 'PJT'   | 'SX33L'           | 'EU(V1)'     | 'EU(V1)'  | 'IC'  | ''      | ''                | 'S2MF-VINCENT'   | 'PJT_SX33L.pdf'                       | ''            | ''  | ''         | ''      | '20130719' | ''    
 'SMCJ60(C)A-13-F' | 'SMLF'    | 'IC'     | 'BCSMCJ60Z00'(!) = ''              | ''             | 'BCSMCJ60Z00' |'D2723_SMCXD'| 'DIODE SMD SMCJ60(C)A-13-F(60V,1500W,SMC)' | 'DDS'   | 'SMCJ60(C)A-13-F' | 'EP(V1)'     | ''        | 'IC'  | ''      | ''                | 'MF1R-DENNY'     | 'SMCJ5-0-C-A_SMCJ170-C-A_REV18-2.pdf' | ''            | ''  | ''         | ''      | '20140207' | ''    
 'SMCJ60(C)A-13-F' | 'SMLF'    | 'EMPTY'  | 'BCSMCJ60Z00'(!) = ''              | ''             | 'BCSMCJ60Z00' |'D2723_SMCXD'| 'DIODE SMD SMCJ60(C)A-13-F(60V,1500W,SMC)' | 'DDS'   | 'SMCJ60(C)A-13-F' | 'EP(V1)'     | ''        | 'IC'  | ''      | ''                | 'MF1R-DENNY'     | 'SMCJ5-0-C-A_SMCJ170-C-A_REV18-2.pdf' | ''            | ''  | ''         | ''      | '20140207' | ''    
 'RB720M-30'       | 'SMLF'    | 'IC'     | 'BC720M30Z00'(!) = ''              | ''             | 'BC720M30Z00' |'SOD923'| 'DIODE SMD RB720M-30(30V,0.1A,SCHOTTKY)'   | 'PJT'   | 'RB720M-30'       | 'EP(V1)'     | ''        | 'IC'  | ''      | ''                | 'T2H-GAVEN'      | 'PJT_RB720M-30_REV0.2.pdf'            | ''            | ''  | ''         | ''      | '20140813' | ''    
 'RB720M-30'       | 'SMLF'    | 'EMPTY'  | 'BC720M30Z00'(!) = ''              | ''             | 'BC720M30Z00' |'SOD923'| 'DIODE SMD RB720M-30(30V,0.1A,SCHOTTKY)'   | 'PJT'   | 'RB720M-30'       | 'EP(V1)'     | ''        | 'IC'  | ''      | ''                | 'T2H-GAVEN'      | 'PJT_RB720M-30_REV0.2.pdf'            | ''            | ''  | ''         | ''      | '20140813' | ''    
 'B130LB-13-F'     | 'SMLF'    | 'IC'     | 'BC000130ZE1'(!) = 'End of Design' | 'Comp-Approve' | 'BC000130ZE1' |'D2114XA'| 'DIODE B130LB-13-F(30V 1A SHTKY,SMB)'      | 'DDS'   | 'B130LB-13-F'     | 'EU'         | 'EU'      | 'IC'  | ''      | ''                | 'T6MG-MARK'      | 'DDS_B130LB-13-F_REV11-2.pdf'         | ''            | ''  | ''         | ''      | '20141211' | ''    
 'B130LB-13-F'     | 'SMLF'    | 'EMPTY'  | 'BC000130ZE1'(!) = 'End of Design' | 'Comp-Approve' | 'BC000130ZE1' |'D2114XA'| 'DIODE B130LB-13-F(30V 1A SHTKY,SMB)'      | 'DDS'   | 'B130LB-13-F'     | 'EU'         | 'EU'      | 'IC'  | ''      | ''                | 'T6MG-MARK'      | 'DDS_B130LB-13-F_REV11-2.pdf'         | ''            | ''  | ''         | ''      | '20141211' | ''    
 'B260-13-F'       | 'SMLF'    | 'IC'     | 'BC000260Z02'(!) = ''              | ''             | 'BC000260Z02' |'D2114XA'| 'DIODE SMB B260-13-F(60V,2.0A)'            | 'DDS'   | 'B260-13-F'       | 'EP(V1)'     | 'EP(V1)'  | 'IC'  | ''      | ''                | 'T2H-GAVEN'      | 'DDS_B260-13-F.pdf'                   | ''            | ''  | ''         | ''      | '20150325' | ''    
 'B260-13-F'       | 'SMLF'    | 'EMPTY'  | 'BC000260Z02'(!) = ''              | ''             | 'BC000260Z02' |'D2114XA'| 'DIODE SMB B260-13-F(60V,2.0A)'            | 'DDS'   | 'B260-13-F'       | 'EP(V1)'     | 'EP(V1)'  | 'IC'  | ''      | ''                | 'T2H-GAVEN'      | 'DDS_B260-13-F.pdf'                   | ''            | ''  | ''         | ''      | '20150325' | ''    
 'B3100-13-F'      | 'SMLF'    | 'IC'     | 'BC310013Z00'(!) = ''              | ''             | 'BC310013Z00' |'D2723_SMCXD'| 'DIODE SMD B3100-13-F (100V,3A)SCHOTKY'    | 'DDS'   | 'B3100-13-F'      | 'EP(V1)'     | ''        | 'IC'  | ''      | ''                | 'T2R-AARON'      | 'DDS_B370-B3100_REV14-2.pdf'          | ''            | ''  | ''         | ''      | '20150327' | ''    
 'B3100-13-F'      | 'SMLF'    | 'EMPTY'  | 'BC310013Z00'(!) = ''              | ''             | 'BC310013Z00' |'D2723_SMCXD'| 'DIODE SMD B3100-13-F (100V,3A)SCHOTKY'    | 'DDS'   | 'B3100-13-F'      | 'EP(V1)'     | ''        | 'IC'  | ''      | ''                | 'T2R-AARON'      | 'DDS_B370-B3100_REV14-2.pdf'          | ''            | ''  | ''         | ''      | '20150327' | ''    
 'B340B-13-F'      | 'SMLF'    | 'IC'     | 'BC0B340BZ15'(!) = ''              | ''             | 'BC0B340BZ15' |'D2114A'| 'DIODE B340B-13-F(40V.3A)SMD'              | 'DDS'   | 'B340B-13-F'      | ''           | 'EP'      | 'IC'  | ''      | ''                | 'JSA-MEALY'      | 'B340B-13-F.pdf'                      | ''            | ''  | ''         | ''      | '20150904' | ''    
 'B340B-13-F'      | 'SMLF'    | 'EMPTY'  | 'BC0B340BZ15'(!) = ''              | ''             | 'BC0B340BZ15' |'D2114A'| 'DIODE B340B-13-F(40V.3A)SMD'              | 'DDS'   | 'B340B-13-F'      | ''           | 'EP'      | 'IC'  | ''      | ''                | 'JSA-MEALY'      | 'B340B-13-F.pdf'                      | ''            | ''  | ''         | ''      | '20150904' | ''    
 'B340A-13-F'      | 'SMLF'    | 'IC'     | 'BC000340Z30'(!) = ''              | ''             | 'BC000340Z30' |'D2010XF'| 'DIODE SMD B340A-13-F(40V,3A)SCHOTTKY'     | 'DDS'   | 'B340A-13-F'      | 'EP(V1)'     | 'EP(V1)'  | 'IC'  | ''      | ''                | 'S5B-ROSSI'      | 'DDS_B340A-13-F.pdf'                  | ''            | ''  | ''         | ''      | '20151231' | ''    
 'B340A-13-F'      | 'SMLF'    | 'EMPTY'  | 'BC000340Z30'(!) = ''              | ''             | 'BC000340Z30' |'D2010XF'| 'DIODE SMD B340A-13-F(40V,3A)SCHOTTKY'     | 'DDS'   | 'B340A-13-F'      | 'EP(V1)'     | 'EP(V1)'  | 'IC'  | ''      | ''                | 'S5B-ROSSI'      | 'DDS_B340A-13-F.pdf'                  | ''            | ''  | ''         | ''      | '20151231' | ''    
 'RB161SS-20T2R'   | 'SMLF'    | 'IC'     | 'BC0161SS000'(!) = 'End of Design' | 'Comp-Approve' | 'BC0161SS000' |'D0603_RB161SS-20T2R'| 'DIODE SMD RB161SS-20T2R(30V,1A)SCHOTTKY'  | 'ROH'   | 'RB161SS-20T2R'   | 'EP(V1)'     | ''        | 'IC'  | ''      | ''                | 'F06-SHERRY'     | 'ROH_RB161SS-20T2R.pdf'               | ''            | ''  | ''         | ''      | '20160308' | ''    
 'RB161SS-20T2R'   | 'SMLF'    | 'EMPTY'  | 'BC0161SS000'(!) = 'End of Design' | 'Comp-Approve' | 'BC0161SS000' |'D0603_RB161SS-20T2R'| 'DIODE SMD RB161SS-20T2R(30V,1A)SCHOTTKY'  | 'ROH'   | 'RB161SS-20T2R'   | 'EP(V1)'     | ''        | 'IC'  | ''      | ''                | 'F06-SHERRY'     | 'ROH_RB161SS-20T2R.pdf'               | ''            | ''  | ''         | ''      | '20160308' | ''    
 'RB520S30'        | 'SMLF'    | 'IC'     | 'BC520S30Z01'(!) = ''              | ''             | 'BC520S30Z01' |'SOD523_1-2X0-8'| 'DIODE SMD RB520S30(30V,200MA)'            | 'NXP'   | 'RB520S30'        | 'EP(V1)'     | ''        | 'IC'  | ''      | ''                | 'QS8204-8i-SEAN' | 'NXP_RB520S30.pdf'                    | ''            | ''  | ''         | ''      | '20160804' | ''    
 'RB520S30'        | 'SMLF'    | 'EMPTY'  | 'BC520S30Z01'(!) = ''              | ''             | 'BC520S30Z01' |'SOD523_1-2X0-8'| 'DIODE SMD RB520S30(30V,200MA)'            | 'NXP'   | 'RB520S30'        | 'EP(V1)'     | ''        | 'IC'  | ''      | ''                | 'QS8204-8i-SEAN' | 'NXP_RB520S30.pdf'                    | ''            | ''  | ''         | ''      | '20160804' | ''    
 'RB161M-20TR'     | 'SMLF'    | 'IC'     | 'BC161M20Z06'(!) = ''              | ''             | 'BC161M20Z06' |'SOD123_2-6X1-6'| 'DIODE SMD RB161M-20TR(20V,1A,SCHOTTY)'    | 'ROH'   | 'RB161M-20TR'     | 'EP'         | 'EP(V1)'  | 'IC'  | ''      | ''                | 'UH3M-KEVIN'     | 'ROH_RB161M-20TR_JUN-30-2009.pdf'     | ''            | ''  | ''         | ''      | '20160809' | ''    
 'RB161M-20TR'     | 'SMLF'    | 'EMPTY'  | 'BC161M20Z06'(!) = ''              | ''             | 'BC161M20Z06' |'SOD123_2-6X1-6'| 'DIODE SMD RB161M-20TR(20V,1A,SCHOTTY)'    | 'ROH'   | 'RB161M-20TR'     | 'EP'         | 'EP(V1)'  | 'IC'  | ''      | ''                | 'UH3M-KEVIN'     | 'ROH_RB161M-20TR_JUN-30-2009.pdf'     | ''            | ''  | ''         | ''      | '20160809' | ''    
 'RB161MM-20TR'    | 'SMLF'    | 'IC'     | 'BC000161Z00'(!) = ''              | ''             | 'BC000161Z00' |'SOD123_2-6X1-6'| 'DIODE SMD RB161MM-20TR(20V,1A,SCHOTTY)'   | 'ROH'   | 'RB161MM-20TR'    | 'EU(V1)'     | ''        | 'IC'  | ''      | ''                | 'UH3M-KEVIN'     | 'ROH_RB161MM-20TR_revA_201408.pdf'    | ''            | ''  | ''         | ''      | '20160818' | ''    
 'RB161MM-20TR'    | 'SMLF'    | 'EMPTY'  | 'BC000161Z00'(!) = ''              | ''             | 'BC000161Z00' |'SOD123_2-6X1-6'| 'DIODE SMD RB161MM-20TR(20V,1A,SCHOTTY)'   | 'ROH'   | 'RB161MM-20TR'    | 'EU(V1)'     | ''        | 'IC'  | ''      | ''                | 'UH3M-KEVIN'     | 'ROH_RB161MM-20TR_revA_201408.pdf'    | ''            | ''  | ''         | ''      | '20160818' | ''    
 'MB310'           | 'SMLF'    | 'IC'     | 'BC000310000'(!) = ''              | ''             | 'BC000310000' |'D2723_SMCXG'| 'DIODE SMD MB310(100V,3A)SCHOTTKY'         | 'PJT'   | 'MB310'           | 'EP(V1)'     | ''        | 'IC'  | ''      | ''                | 'T2H-HSUEHYEN'   | 'PJT_MB34_SERIESRE_V6-13-2016.pdf'    | ''            | ''  | ''         | ''      | '20161220' | ''    
 'MB310'           | 'SMLF'    | 'EMPTY'  | 'BC000310000'(!) = ''              | ''             | 'BC000310000' |'D2723_SMCXG'| 'DIODE SMD MB310(100V,3A)SCHOTTKY'         | 'PJT'   | 'MB310'           | 'EP(V1)'     | ''        | 'IC'  | ''      | ''                | 'T2H-HSUEHYEN'   | 'PJT_MB34_SERIESRE_V6-13-2016.pdf'    | ''            | ''  | ''         | ''      | '20161220' | ''    
 'MBRS3100T3G'     | 'SMLF'    | 'IC'     | 'BC003100Z00'(!) = ''              | ''             | 'BC003100Z00' |'D2723_SMCXJ'| 'DIODE SMD MBRS3100T3G(100V,3A)AEC'        | 'ONS'   | 'MBRS3100T3G'     | 'EP(V1)'     | ''        | 'IC'  | ''      | ''                | 'T2H-HSUEH-YEN'  | 'ONS_MBRS3100T3G.pdf'                 | ''            | ''  | ''         | ''      | '20161228' | ''    
 'MBRS3100T3G'     | 'SMLF'    | 'EMPTY'  | 'BC003100Z00'(!) = ''              | ''             | 'BC003100Z00' |'D2723_SMCXJ'| 'DIODE SMD MBRS3100T3G(100V,3A)AEC'        | 'ONS'   | 'MBRS3100T3G'     | 'EP(V1)'     | ''        | 'IC'  | ''      | ''                | 'T2H-HSUEH-YEN'  | 'ONS_MBRS3100T3G.pdf'                 | ''            | ''  | ''         | ''      | '20161228' | ''    
 'S310'            | 'SMLF'    | 'IC'     | 'BC000310001'(!) = ''              | ''             | 'BC000310001' |'D2723_SMCXI'| 'DIODE SMD S310(100V,3A,2.27W)SCHOTTKY'    | 'FAC'   | 'S310'            | 'EP(V1)'     | ''        | 'IC'  | ''      | ''                | 'T2H-HSUEH-YEN'  | 'FAC_S310.pdf'                        | ''            | ''  | ''         | ''      | '20161228' | ''    
 'S310'            | 'SMLF'    | 'EMPTY'  | 'BC000310001'(!) = ''              | ''             | 'BC000310001' |'D2723_SMCXI'| 'DIODE SMD S310(100V,3A,2.27W)SCHOTTKY'    | 'FAC'   | 'S310'            | 'EP(V1)'     | ''        | 'IC'  | ''      | ''                | 'T2H-HSUEH-YEN'  | 'FAC_S310.pdf'                        | ''            | ''  | ''         | ''      | '20161228' | ''    
 'B140HW-7'        | 'SMLF'    | 'IC'     | 'BC000140Z05'(!) = 'End of Design' | 'Comp-Approve' | 'BC000140Z05' |'SOD123_2-7X1-55XA'| 'DIODE SMD B140HW-7(40V,1A)SCHOTTKY'       | 'DDS'   | 'B140HW-7'        | 'EP(V1)'     | 'EP(V1)'  | 'IC'  | ''      | ''                | 'JBE-STAN'       | 'DDS_B140HW-7.pdf'                    | ''            | ''  | ''         | ''      | '20170126' | ''    
 'B140HW-7'        | 'SMLF'    | 'EMPTY'  | 'BC000140Z05'(!) = 'End of Design' | 'Comp-Approve' | 'BC000140Z05' |'SOD123_2-7X1-55XA'| 'DIODE SMD B140HW-7(40V,1A)SCHOTTKY'       | 'DDS'   | 'B140HW-7'        | 'EP(V1)'     | 'EP(V1)'  | 'IC'  | ''      | ''                | 'JBE-STAN'       | 'DDS_B140HW-7.pdf'                    | ''            | ''  | ''         | ''      | '20170126' | ''    
 'SS1040'          | 'SMLF'    | 'IC'     | 'BCSS1040005'(!) = ''              | ''             | 'BCSS1040005' |'SOD123_2-65X1-6'| 'DIODE SMD SS1040(40V,1A,SCHOTTKY)'        | 'PJT'   | 'SS1040'          | 'EP(V1)'     | 'EP(V1)'  | 'IC'  | ''      | ''                | 'JBE-STAN'       | 'PJT_SS1040.pdf'                      | ''            | ''  | ''         | ''      | '20170202' | ''    
 'SS1040'          | 'SMLF'    | 'EMPTY'  | 'BCSS1040005'(!) = ''              | ''             | 'BCSS1040005' |'SOD123_2-65X1-6'| 'DIODE SMD SS1040(40V,1A,SCHOTTKY)'        | 'PJT'   | 'SS1040'          | 'EP(V1)'     | 'EP(V1)'  | 'IC'  | ''      | ''                | 'JBE-STAN'       | 'PJT_SS1040.pdf'                      | ''            | ''  | ''         | ''      | '20170202' | ''    
 'RB551V30 T/R13'  | 'SMLF'    | 'IC'     | 'BCRB551VZ00'(!) = ''              | ''             | 'BCRB551VZ00' |'SOD323XD'| 'DIODE SMD RB551V30 T/R(30V,500MA,SOD323)' | 'PJT'   | 'RB551V30 T/R13'  | 'EP(V1)'     | 'EP(V1)'  | 'IC'  | ''      | ''                | 'CAVIUM-MARCUS'  | 'PJT_RB551V30TR13.pdf'                | ''            | ''  | ''         | ''      | '20170329' | ''    
 'RB551V30 T/R13'  | 'SMLF'    | 'EMPTY'  | 'BCRB551VZ00'(!) = ''              | ''             | 'BCRB551VZ00' |'SOD323XD'| 'DIODE SMD RB551V30 T/R(30V,500MA,SOD323)' | 'PJT'   | 'RB551V30 T/R13'  | 'EP(V1)'     | 'EP(V1)'  | 'IC'  | ''      | ''                | 'CAVIUM-MARCUS'  | 'PJT_RB551V30TR13.pdf'                | ''            | ''  | ''         | ''      | '20170329' | ''    
 'NSR20406NXT5G'   | 'SMLF'    | 'IC'     | 'BC020406Z00'(!) = ''              | 'End of Life'  | 'BC020406Z00' |'D_DSN2_0603_EOL'| 'DIODE SMD NSR20406NXT5G(40V,2A)SCHOTTKY'  | 'ONS'   | 'NSR20406NXT5G'   | 'EP(V1)'     | ''        | 'IC'  | ''      | ''                | 'T2N-HSUEH-YEN'  | 'ONS_NSR20406NXT5G.pdf'               | ''            | ''  | ''         | ''      | '20170705' | ''    
 'NSR20406NXT5G'   | 'SMLF'    | 'EMPTY'  | 'BC020406Z00'(!) = ''              | 'End of Life'  | 'BC020406Z00' |'D_DSN2_0603_EOL'| 'DIODE SMD NSR20406NXT5G(40V,2A)SCHOTTKY'  | 'ONS'   | 'NSR20406NXT5G'   | 'EP(V1)'     | ''        | 'IC'  | ''      | ''                | 'T2N-HSUEH-YEN'  | 'ONS_NSR20406NXT5G.pdf'               | ''            | ''  | ''         | ''      | '20170705' | ''    
 'NRVB1H100SFT3G'  | 'SMLF'    | 'IC'     | 'BC100SFTZ00'(!) = ''              | ''             | 'BC100SFTZ00' |'SOD123XF'| 'DIODE SMD NRVB1H100S(100V,50A,SOD-123FL)' | 'ONS'   | 'NRVB1H100SFT3G'  | 'EP(V1)'     | 'EP(V1)'  | 'IC'  | ''      | ''                | 'T2N-JANE'       | 'MBR1H100SFT3G_NRVB1H100SFT3G.pdf'    | ''            | ''  | ''         | ''      | '20170817' | ''    
 'NRVB1H100SFT3G'  | 'SMLF'    | 'EMPTY'  | 'BC100SFTZ00'(!) = ''              | ''             | 'BC100SFTZ00' |'SOD123XF'| 'DIODE SMD NRVB1H100S(100V,50A,SOD-123FL)' | 'ONS'   | 'NRVB1H100SFT3G'  | 'EP(V1)'     | 'EP(V1)'  | 'IC'  | ''      | ''                | 'T2N-JANE'       | 'MBR1H100SFT3G_NRVB1H100SFT3G.pdf'    | ''            | ''  | ''         | ''      | '20170817' | ''    
 'SBR2U30SA'       | 'SMLF'    | 'IC'     | 'BC2U30SAZ00'(!) = ''              | ''             | 'BC2U30SAZ00' |'D2010XF'| 'DIODE SMD SBR2U30SA(30V,2A,SCHOTTKY,SMA)' | 'DDS'   | 'SBR2U30SA-13'    | 'EP(V1)'     | ''        | 'IC'  | ''      | ''                | 'S2LR-YIMIN'     | 'DDS_SBR2U30SA.pdf'                   | ''            | ''  | ''         | ''      | '20170919' | ''    
 'SBR2U30SA'       | 'SMLF'    | 'EMPTY'  | 'BC2U30SAZ00'(!) = ''              | ''             | 'BC2U30SAZ00' |'D2010XF'| 'DIODE SMD SBR2U30SA(30V,2A,SCHOTTKY,SMA)' | 'DDS'   | 'SBR2U30SA-13'    | 'EP(V1)'     | ''        | 'IC'  | ''      | ''                | 'S2LR-YIMIN'     | 'DDS_SBR2U30SA.pdf'                   | ''            | ''  | ''         | ''      | '20170919' | ''    
 'RB521S30'        | 'SMLF'    | 'IC'     | 'BC521S30Z00'(!) = ''              | ''             | 'BC521S30Z00' |'SOD523_1-2X0-8XB'| 'DIODE SCHOTTKY RB521S30(30V,0.2A)'        | 'PJT'   | 'RB521S30'        | 'EP(V1)'     | 'EP(V1)'  | 'IC'  | ''      | ''                | 'F09-SEAN'       | 'PJT_RB521S30.pdf'                    | ''            | ''  | ''         | ''      | '20170921' | ''    
 'RB521S30'        | 'SMLF'    | 'EMPTY'  | 'BC521S30Z00'(!) = ''              | ''             | 'BC521S30Z00' |'SOD523_1-2X0-8XB'| 'DIODE SCHOTTKY RB521S30(30V,0.2A)'        | 'PJT'   | 'RB521S30'        | 'EP(V1)'     | 'EP(V1)'  | 'IC'  | ''      | ''                | 'F09-SEAN'       | 'PJT_RB521S30.pdf'                    | ''            | ''  | ''         | ''      | '20170921' | ''    
 'BAT54HT1G'       | 'SMLF'    | 'IC'     | 'BC54HT1GZ00'(!) = ''              | ''             | 'BC54HT1GZ00' |'SOD323XK'| 'DIODE SMD BAT54HT1G(30V,0.2A,S0D323)'     | 'FAC'   | 'BAT54HT1G'       | 'EP(V1)'     | 'EP(V1)'  | 'IC'  | ''      | ''                | 'T2HV-EASON'     | 'FAC_BAT54HT1G.pdf'                   | ''            | ''  | ''         | ''      | '20161220' | ''    
 'BAT54HT1G'       | 'SMLF'    | 'EMPTY'  | 'BC54HT1GZ00'(!) = ''              | ''             | 'BC54HT1GZ00' |'SOD323XK'| 'DIODE SMD BAT54HT1G(30V,0.2A,S0D323)'     | 'FAC'   | 'BAT54HT1G'       | 'EP(V1)'     | 'EP(V1)'  | 'IC'  | ''      | ''                | 'T2HV-EASON'     | 'FAC_BAT54HT1G.pdf'                   | ''            | ''  | ''         | ''      | '20161220' | ''    
 'MBR130T1G'       | 'SMLF'    | 'IC'     | 'BCMBR130Z00'(!) = ''              | ''             | 'BCMBR130Z00' |'SOD123XE'| 'DIODE SMD MBR130T1G(30V,1A,SCHOTTKY)'     | 'ONS'   | 'MBR130T1G'       | 'EP(V1)'     | ''        | 'IC'  | ''      | ''                | 'T2N-MARK'       | 'ONS_MBR130T1G.pdf'                   | ''            | ''  | ''         | ''      | '20171027' | ''    
 'MBR130T1G'       | 'SMLF'    | 'EMPTY'  | 'BCMBR130Z00'(!) = ''              | ''             | 'BCMBR130Z00' |'SOD123XE'| 'DIODE SMD MBR130T1G(30V,1A,SCHOTTKY)'     | 'ONS'   | 'MBR130T1G'       | 'EP(V1)'     | ''        | 'IC'  | ''      | ''                | 'T2N-MARK'       | 'ONS_MBR130T1G.pdf'                   | ''            | ''  | ''         | ''      | '20171027' | ''    
 'RB521S30FN2'     | 'SMLF'    | 'IC'     | 'BCRB521SZ00'(!) = ''              | ''             | 'BCRB521SZ00' |'D0402_RB521S30FN2'| 'DIODE SMD RB521S30FN2(30V,0.2A,SCHOTTKY)' | 'PJT'   | 'RB521S30FN2'     | 'EP(V1)'     | ''        | 'IC'  | ''      | ''                | 'S5G-JUSTIN'     | 'PJT_RB521S30FN2.pdf'                 | ''            | ''  | ''         | ''      | '20180226' | ''    
 'RB521S30FN2'     | 'SMLF'    | 'EMPTY'  | 'BCRB521SZ00'(!) = ''              | ''             | 'BCRB521SZ00' |'D0402_RB521S30FN2'| 'DIODE SMD RB521S30FN2(30V,0.2A,SCHOTTKY)' | 'PJT'   | 'RB521S30FN2'     | 'EP(V1)'     | ''        | 'IC'  | ''      | ''                | 'S5G-JUSTIN'     | 'PJT_RB521S30FN2.pdf'                 | ''            | ''  | ''         | ''      | '20180226' | ''    
 'RB521CM-30T2R'   | 'SMLF'    | 'IC'     | 'BCRB521CZ01'(!) = ''              | ''             | 'BCRB521CZ01' |'SOD923_0-86X0-6'| 'DIODESMD RB521CM-30T2R(30V,0.1A,SCHOTTKY' | 'ROH'   | 'RB521CM-30T2R'   | 'EP(V1)'     | 'EP(V1)'  | 'IC'  | ''      | ''                | 'S5G-JUSTIN'     | 'ROH_RB521CM-30T2R.pdf'               | ''            | ''  | ''         | ''      | '20180227' | ''    
 'RB521CM-30T2R'   | 'SMLF'    | 'EMPTY'  | 'BCRB521CZ01'(!) = ''              | ''             | 'BCRB521CZ01' |'SOD923_0-86X0-6'| 'DIODESMD RB521CM-30T2R(30V,0.1A,SCHOTTKY' | 'ROH'   | 'RB521CM-30T2R'   | 'EP(V1)'     | 'EP(V1)'  | 'IC'  | ''      | ''                | 'S5G-JUSTIN'     | 'ROH_RB521CM-30T2R.pdf'               | ''            | ''  | ''         | ''      | '20180227' | ''    
 'BAS3010S-02LRH'  | 'SMLF'    | 'IC'     | 'BC3010SZ000'(!) = ''              | ''             | 'BC3010SZ000' |'D0402_BAS3010S-02LRH'| 'DIODE SMD BAS3010S-02LRH(30V,1A)'         | 'SNI'   | 'BAS3010S-02LRH'  | 'EP(V1)'     | ''        | 'IC'  | ''      | ''                | 'T2N-CARLOS'     | 'SNI_BAS3010S-02LRH.pdf'              | ''            | ''  | ''         | ''      | '20180329' | ''    
 'BAS3010S-02LRH'  | 'SMLF'    | 'EMPTY'  | 'BC3010SZ000'(!) = ''              | ''             | 'BC3010SZ000' |'D0402_BAS3010S-02LRH'| 'DIODE SMD BAS3010S-02LRH(30V,1A)'         | 'SNI'   | 'BAS3010S-02LRH'  | 'EP(V1)'     | ''        | 'IC'  | ''      | ''                | 'T2N-CARLOS'     | 'SNI_BAS3010S-02LRH.pdf'              | ''            | ''  | ''         | ''      | '20180329' | ''    
 'PMEG4002ELD'     | 'SMLF'    | 'IC'     | 'BC4002ELZ00'(!) = ''              | ''             | 'BC4002ELZ00' |'SOD882D'| 'DIODE PMEG4002ELD(40V,0.2A)(SOD882D)'     | 'NXP'   | 'PMEG4002ELD'     | 'EP(V1)'     | 'EP(V1)'  | 'IC'  | ''      | ''                | 'S1F-STANLEY'    | 'NXP_PMEG4002ELD_Rev 1.pdf'           | ''            | ''  | ''         | ''      | '20130923' | ''    
 'PMEG4002ELD'     | 'SMLF'    | 'EMPTY'  | 'BC4002ELZ00'(!) = ''              | ''             | 'BC4002ELZ00' |'SOD882D'| 'DIODE PMEG4002ELD(40V,0.2A)(SOD882D)'     | 'NXP'   | 'PMEG4002ELD'     | 'EP(V1)'     | 'EP(V1)'  | 'IC'  | ''      | ''                | 'S1F-STANLEY'    | 'NXP_PMEG4002ELD_Rev 1.pdf'           | ''            | ''  | ''         | ''      | '20130923' | ''    
 '5.0SMDJ12A'      | 'SMLF'    | 'IC'     | 'BCMDJ12AZ00'(!) = ''              | ''             | 'BCMDJ12AZ00' |'D_SMDJ60A'| 'DIODE SMD 5.0SMDJ12A(12V,252A,5000W)'     | 'LFI'   | '5.0SMDJ12A'      | 'EP(V1)'     | ''        | 'IC'  | ''      | ''                | 'T6U-JACK'       | 'LFI_5.0SMDJ12A.pdf'                  | ''            | ''  | ''         | ''      | '20180717' | ''    
 '5.0SMDJ12A'      | 'SMLF'    | 'EMPTY'  | 'BCMDJ12AZ00'(!) = ''              | ''             | 'BCMDJ12AZ00' |'D_SMDJ60A'| 'DIODE SMD 5.0SMDJ12A(12V,252A,5000W)'     | 'LFI'   | '5.0SMDJ12A'      | 'EP(V1)'     | ''        | 'IC'  | ''      | ''                | 'T6U-JACK'       | 'LFI_5.0SMDJ12A.pdf'                  | ''            | ''  | ''         | ''      | '20180717' | ''    
 'PMEG2005EL'      | 'SMLF'    | 'IC'     | 'BC2005ELZ00'(!) = ''              | ''             | 'BC2005ELZ00' |'SOD882_0-985X0-585'| 'DIODE PMEG2005EL(20V,0.5A)(SOD882)'       | 'NXP'   | 'PMEG2005EL'      | 'EP(V1)'     | 'EP(V1)'  | 'IC'  | ''      | ''                | 'JB4-JOHNNY'     | 'NXP_PMEG2005EL.pdf'                  | ''            | ''  | ''         | ''      | '20180723' | ''    
 'PMEG2005EL'      | 'SMLF'    | 'EMPTY'  | 'BC2005ELZ00'(!) = ''              | ''             | 'BC2005ELZ00' |'SOD882_0-985X0-585'| 'DIODE PMEG2005EL(20V,0.5A)(SOD882)'       | 'NXP'   | 'PMEG2005EL'      | 'EP(V1)'     | 'EP(V1)'  | 'IC'  | ''      | ''                | 'JB4-JOHNNY'     | 'NXP_PMEG2005EL.pdf'                  | ''            | ''  | ''         | ''      | '20180723' | ''    
 'DSF01S30SL'      | 'SMLF'    | 'IC'     | 'BC1S30SLZ00'(!) = ''              | ''             | 'BC1S30SLZ00' |'SOD962_0-62X0-32'| 'DIODE SMD DSF01S30SL(30V,0.1A,SCHOTTKY)'  | 'TOS'   | 'DSF01S30SL'      | 'EP(V1)'     | ''        | 'IC'  | ''      | ''                | 'F0B-HANK'       | 'TOS_DSF01S30SL.pdf'                  | ''            | ''  | ''         | ''      | '20180822' | ''    
 'DSF01S30SL'      | 'SMLF'    | 'EMPTY'  | 'BC1S30SLZ00'(!) = ''              | ''             | 'BC1S30SLZ00' |'SOD962_0-62X0-32'| 'DIODE SMD DSF01S30SL(30V,0.1A,SCHOTTKY)'  | 'TOS'   | 'DSF01S30SL'      | 'EP(V1)'     | ''        | 'IC'  | ''      | ''                | 'F0B-HANK'       | 'TOS_DSF01S30SL.pdf'                  | ''            | ''  | ''         | ''      | '20180822' | ''    
 'BZT52C4V7LP-7'   | 'SMLF'    | 'IC'     | 'BD52C4V7Z00'(!) = ''              | ''             | 'BD52C4V7Z00' |'D0402XA'| 'DIODE ZENER BZT52C4V7LP-7(4.7V,0.25W)'    | 'DDS'   | 'BZT52C4V7LP-7'   | 'EP(V1)'     | ''        | 'IC'  | ''      | ''                | 'S5U-JOANNE'     | 'DDS_BZT52C4V7LP-7.pdf'               | ''            | ''  | ''         | ''      | '20181217' | ''    
 'BZT52C4V7LP-7'   | 'SMLF'    | 'EMPTY'  | 'BD52C4V7Z00'(!) = ''              | ''             | 'BD52C4V7Z00' |'D0402XA'| 'DIODE ZENER BZT52C4V7LP-7(4.7V,0.25W)'    | 'DDS'   | 'BZT52C4V7LP-7'   | 'EP(V1)'     | ''        | 'IC'  | ''      | ''                | 'S5U-JOANNE'     | 'DDS_BZT52C4V7LP-7.pdf'               | ''            | ''  | ''         | ''      | '20181217' | ''    
 'BAS70-02L'       | 'SMLF'    | 'IC'     | 'BC0BAS70Z15'(!) = ''              | ''             | 'BC0BAS70Z15' |'D0402_BAS3010S-02LRH_H20'| 'DIODE SMD BAS70-02L(70V,0.07A,0.25W)'     | 'SNI'   | 'BAS70-02L'       | 'EP(V1)'     | 'EP(V1)'  | 'IC'  | ''      | ''                | 'T2N-CHEER'      | 'SNI_BAS70-02L.pdf'                   | ''            | ''  | ''         | ''      | '20190403' | ''    
 'BAS70-02L'       | 'SMLF'    | 'EMPTY'  | 'BC0BAS70Z15'(!) = ''              | ''             | 'BC0BAS70Z15' |'D0402_BAS3010S-02LRH_H20'| 'DIODE SMD BAS70-02L(70V,0.07A,0.25W)'     | 'SNI'   | 'BAS70-02L'       | 'EP(V1)'     | 'EP(V1)'  | 'IC'  | ''      | ''                | 'T2N-CHEER'      | 'SNI_BAS70-02L.pdf'                   | ''            | ''  | ''         | ''      | '20190403' | ''    
 'MMSD701T1G'      | 'SMLF'    | 'IC'     | 'BAM701T0000'(!) = ''              | 'End of Life'  | 'BAM701T0000' |'SOD123XE_EOL'| 'TRANS MOS MMSD701T1G(70V,0.2A,0,225W)'    | 'ONS'   | 'MMSD701T1G'      | 'EP(V1)'     | ''        | 'IC'  | ''      | ''                | 'T2N-JW'         | 'ONS_MMSD701T1G.pdf'                  | ''            | ''  | ''         | ''      | '20190417' | ''    
 'MMSD701T1G'      | 'SMLF'    | 'EMPTY'  | 'BAM701T0000'(!) = ''              | 'End of Life'  | 'BAM701T0000' |'SOD123XE_EOL'| 'TRANS MOS MMSD701T1G(70V,0.2A,0,225W)'    | 'ONS'   | 'MMSD701T1G'      | 'EP(V1)'     | ''        | 'IC'  | ''      | ''                | 'T2N-JW'         | 'ONS_MMSD701T1G.pdf'                  | ''            | ''  | ''         | ''      | '20190417' | ''    
 'P4SMAJ13A'       | 'SMLF'    | 'IC'     | 'BCMAJ13AZ03'(!) = ''              | ''             | 'BCMAJ13AZ03' |'D2010XH'| 'DIODE SMD P4SMAJ13A (400W,13V)'           | 'PJT'   | 'P4SMAJ13A'       | 'EP(V1)'     | 'EP(V1)'  | 'IC'  | ''      | ''                | 'F0C-ABER'       | 'PJT_P4SMAJ13A.pdf'                   | ''            | ''  | ''         | ''      | '20190521' | ''    
 'P4SMAJ13A'       | 'SMLF'    | 'EMPTY'  | 'BCMAJ13AZ03'(!) = ''              | ''             | 'BCMAJ13AZ03' |'D2010XH'| 'DIODE SMD P4SMAJ13A (400W,13V)'           | 'PJT'   | 'P4SMAJ13A'       | 'EP(V1)'     | 'EP(V1)'  | 'IC'  | ''      | ''                | 'F0C-ABER'       | 'PJT_P4SMAJ13A.pdf'                   | ''            | ''  | ''         | ''      | '20190521' | ''    
 'PMEG4002EL'      | 'SMLF'    | 'IC'     | 'BC4002ELZ01'(!) = ''              | ''             | 'BC4002ELZ01' |'SOD882_0-985X0-585'| 'DIODE PMEG4002EL (40V,0.2A) (SOD882)'     | 'NXP'   | 'PMEG4002EL'      | 'EP(V1)'     | ''        | 'IC'  | ''      | ''                | 'T2C-CARLOS'     | 'NXP_PMEG4002EL.pdf'                  | ''            | ''  | ''         | ''      | '20190603' | ''    
 'PMEG4002EL'      | 'SMLF'    | 'EMPTY'  | 'BC4002ELZ01'(!) = ''              | ''             | 'BC4002ELZ01' |'SOD882_0-985X0-585'| 'DIODE PMEG4002EL (40V,0.2A) (SOD882)'     | 'NXP'   | 'PMEG4002EL'      | 'EP(V1)'     | ''        | 'IC'  | ''      | ''                | 'T2C-CARLOS'     | 'NXP_PMEG4002EL.pdf'                  | ''            | ''  | ''         | ''      | '20190603' | ''    
 'SDM2U40CSP-7B'   | 'SMLF'    | 'IC'     | 'BCU40CSPU02'(!) = ''              | ''             | 'BCU40CSPU02' |'D_X3-WLB1608-2'| 'DIODE SMD SDM2U40CSP-7B (40V,2A)'         | 'DDS'   | 'SDM2U40CSP-7B'   | 'EP(V1)'     | 'EP(V1)'  | 'IC'  | ''      | ''                | 'F0G-EGBERT'     | 'DDS_SDM2U40CSP-7B.pdf'               | ''            | ''  | ''         | ''      | '20190820' | ''    
 'SDM2U40CSP-7B'   | 'SMLF'    | 'EMPTY'  | 'BCU40CSPU02'(!) = ''              | ''             | 'BCU40CSPU02' |'D_X3-WLB1608-2'| 'DIODE SMD SDM2U40CSP-7B (40V,2A)'         | 'DDS'   | 'SDM2U40CSP-7B'   | 'EP(V1)'     | 'EP(V1)'  | 'IC'  | ''      | ''                | 'F0G-EGBERT'     | 'DDS_SDM2U40CSP-7B.pdf'               | ''            | ''  | ''         | ''      | '20190820' | ''    
 'PMEG1020EA'      | 'SMLF'    | 'IC'     | 'BC1020EAZ00'(!) = ''              | ''             | 'BC1020EAZ00' |'SOD323F_H44'| 'DIODE SMD PMEG1020EA(10V,2A)AEC'          | 'NXP'   | 'PMEG1020EA'      | 'EU(V1)'     | ''        | 'IC'  | ''      | 'PMEG1020EA.msg'  | 'S8I-FRANK'      | 'NXP_PMEG1020EA.pdf'                  | ''            | ''  | ''         | ''      | '20191021' | ''    
 'PMEG1020EA'      | 'SMLF'    | 'EMPTY'  | 'BC1020EAZ00'(!) = ''              | ''             | 'BC1020EAZ00' |'SOD323F_H44'| 'DIODE SMD PMEG1020EA(10V,2A)AEC'          | 'NXP'   | 'PMEG1020EA'      | 'EU(V1)'     | ''        | 'IC'  | ''      | 'PMEG1020EA.msg'  | 'S8I-FRANK'      | 'NXP_PMEG1020EA.pdf'                  | ''            | ''  | ''         | ''      | '20191021' | ''    
 'BAT54WS'         | 'SMLF'    | 'IC'     | 'BCBAT54WZ09'(!) = ''              | ''             | 'BCBAT54WZ09' |'SOD323XD'| 'DIODE SMD BAT54WS(30V,0.2A,SCHOTTKY)'     | 'PJT'   | 'BAT54WS'         | 'EP(V1)'     | 'EP(V1)'  | 'IC'  | ''      | ''                | 'S5C-HOWARD'     | 'PJT_BAT54WS.pdf'                     | ''            | ''  | ''         | ''      | '20191125' | ''    
 'BAT54WS'         | 'SMLF'    | 'EMPTY'  | 'BCBAT54WZ09'(!) = ''              | ''             | 'BCBAT54WZ09' |'SOD323XD'| 'DIODE SMD BAT54WS(30V,0.2A,SCHOTTKY)'     | 'PJT'   | 'BAT54WS'         | 'EP(V1)'     | 'EP(V1)'  | 'IC'  | ''      | ''                | 'S5C-HOWARD'     | 'PJT_BAT54WS.pdf'                     | ''            | ''  | ''         | ''      | '20191125' | ''    
 'SX34F'           | 'SMLF'    | 'IC'     | 'BC00SX34Z01'(!) = ''              | 'End of Life'  | 'BC00SX34Z01' |'D1510_SMAF_EOL'| 'DIODE SMD SX34F(40V,3A,SCHOTTKY)'         | 'PJT'   | 'SX34F'           | 'EP(V1)'     | 'EP(V1)'  | 'IC'  | ''      | ''                | 'S9S-CHRIS'      | 'PJT_SX34F.pdf'                       | ''            | ''  | ''         | ''      | '20200303' | ''    
 'SX34F'           | 'SMLF'    | 'EMPTY'  | 'BC00SX34Z01'(!) = ''              | 'End of Life'  | 'BC00SX34Z01' |'D1510_SMAF_EOL'| 'DIODE SMD SX34F(40V,3A,SCHOTTKY)'         | 'PJT'   | 'SX34F'           | 'EP(V1)'     | 'EP(V1)'  | 'IC'  | ''      | ''                | 'S9S-CHRIS'      | 'PJT_SX34F.pdf'                       | ''            | ''  | ''         | ''      | '20200303' | ''    
 'MBRS540T3G'      | 'SMLF'    | 'IC'     | 'BC000540Z02'(!) = ''              | ''             | 'BC000540Z02' |'D2723_SMCXJ'| 'DIODE SCHOTTKY MBRS540T3G(40V,5A,SMC)'    | 'ONS'   | 'MBRS540T3G'      | 'EP'         | 'EP'      | 'IC'  | ''      | ''                | 'S8A-JAY'        | 'ONS_MBRS540T3G.pdf'                  | ''            | ''  | ''         | ''      | '20200304' | ''    
 'MBRS540T3G'      | 'SMLF'    | 'EMPTY'  | 'BC000540Z02'(!) = ''              | ''             | 'BC000540Z02' |'D2723_SMCXJ'| 'DIODE SCHOTTKY MBRS540T3G(40V,5A,SMC)'    | 'ONS'   | 'MBRS540T3G'      | 'EP'         | 'EP'      | 'IC'  | ''      | ''                | 'S8A-JAY'        | 'ONS_MBRS540T3G.pdf'                  | ''            | ''  | ''         | ''      | '20200304' | ''    
 'BAT760'          | 'SMLF'    | 'IC'     | 'BCBAT760007'(!) = ''              | ''             | 'BCBAT760007' |'SOD323F_H44'| 'DIODE SCHOTTKY BAT760(20V,SOD323)'        | 'PHI'   | 'BAT760'          | 'EP'         | 'EP'      | 'IC'  | ''      | 'BAT760.msg'      | 'S8A-KENNY'      | 'PHI_BAT760.pdf'                      | ''            | ''  | ''         | ''      | '20200309' | ''    
 'BAT760'          | 'SMLF'    | 'EMPTY'  | 'BCBAT760007'(!) = ''              | ''             | 'BCBAT760007' |'SOD323F_H44'| 'DIODE SCHOTTKY BAT760(20V,SOD323)'        | 'PHI'   | 'BAT760'          | 'EP'         | 'EP'      | 'IC'  | ''      | 'BAT760.msg'      | 'S8A-KENNY'      | 'PHI_BAT760.pdf'                      | ''            | ''  | ''         | ''      | '20200309' | ''    
 'BAT46WJ'         | 'SMLF'    | 'IC'     | 'BCBAT46WZ01'(!) = ''              | ''             | 'BCBAT46WZ01' |'SOD323F'| 'DIODE SMD BAT46WJ(100V,2.5A)AEC'          | 'NXE'   | 'BAT46WJ'         | 'EU(V1)'     | ''        | 'IC'  | ''      | ''                | 'S8A-KENNY'      | 'NXE_BAT46WJ.pdf'                     | ''            | ''  | ''         | ''      | '20200312' | ''    
 'BAT46WJ'         | 'SMLF'    | 'EMPTY'  | 'BCBAT46WZ01'(!) = ''              | ''             | 'BCBAT46WZ01' |'SOD323F'| 'DIODE SMD BAT46WJ(100V,2.5A)AEC'          | 'NXE'   | 'BAT46WJ'         | 'EU(V1)'     | ''        | 'IC'  | ''      | ''                | 'S8A-KENNY'      | 'NXE_BAT46WJ.pdf'                     | ''            | ''  | ''         | ''      | '20200312' | ''    
 'MBR1H100SFT3G'   | 'SMLF'    | 'IC'     | 'BC01H100000'(!) = ''              | ''             | 'BC01H100000' |'SOD123_2-7X1-65'| 'DIODE SMD MBR1H100SFT3G(100V,1A)'         | 'ONS'   | 'MBR1H100SFT3G'   | 'EP(V1)'     | 'EP(V1)'  | 'IC'  | ''      | ''                | 'S8A-YC'         | 'ONS_MBR1H100SFT3G.pdf'               | ''            | ''  | ''         | ''      | '20200406' | ''    
 'MBR1H100SFT3G'   | 'SMLF'    | 'EMPTY'  | 'BC01H100000'(!) = ''              | ''             | 'BC01H100000' |'SOD123_2-7X1-65'| 'DIODE SMD MBR1H100SFT3G(100V,1A)'         | 'ONS'   | 'MBR1H100SFT3G'   | 'EP(V1)'     | 'EP(V1)'  | 'IC'  | ''      | ''                | 'S8A-YC'         | 'ONS_MBR1H100SFT3G.pdf'               | ''            | ''  | ''         | ''      | '20200406' | ''    
 'B340-13-F'       | 'SMLF'    | 'IC'     | 'BC00B340Z00'(!) = ''              | ''             | 'BC00B340Z00' |'D2723_SMCXD'| 'DIODE SMD B340-13-F(40V,3A)'              | 'DDS'   | 'B340-13-F'       | 'EU(V1)'     | 'EU(V1)'  | 'IC'  | ''      | ''                | 'S3I-VINCENT'    | 'DDS_B340-13-F.pdf'                   | ''            | ''  | ''         | ''      | '20200620' | ''    
 'B340-13-F'       | 'SMLF'    | 'EMPTY'  | 'BC00B340Z00'(!) = ''              | ''             | 'BC00B340Z00' |'D2723_SMCXD'| 'DIODE SMD B340-13-F(40V,3A)'              | 'DDS'   | 'B340-13-F'       | 'EU(V1)'     | 'EU(V1)'  | 'IC'  | ''      | ''                | 'S3I-VINCENT'    | 'DDS_B340-13-F.pdf'                   | ''            | ''  | ''         | ''      | '20200620' | ''    
 'SDM161645EP3-7'  | 'SMLF'    | 'IC'     | 'BC161645Z00'(!) = ''              | ''             | 'BC161645Z00' |'D_X3-TSN1616-2_1-6X1-6'| 'DIODE SMD SDM161645EP3-7(45V,5A)SCHOTTKY' | 'DDS'   | 'SDM161645EP3-7'  | 'EP(V1)'     | ''        | 'IC'  | ''      | ''                | 'F0E-CHUN'       | 'DDS_SDM161645EP3-7.pdf'              | ''            | ''  | ''         | ''      | '20201106' | ''    
 'SDM161645EP3-7'  | 'SMLF'    | 'EMPTY'  | 'BC161645Z00'(!) = ''              | ''             | 'BC161645Z00' |'D_X3-TSN1616-2_1-6X1-6'| 'DIODE SMD SDM161645EP3-7(45V,5A)SCHOTTKY' | 'DDS'   | 'SDM161645EP3-7'  | 'EP(V1)'     | ''        | 'IC'  | ''      | ''                | 'F0E-CHUN'       | 'DDS_SDM161645EP3-7.pdf'              | ''            | ''  | ''         | ''      | '20201106' | ''    
 'SB34AFC'         | 'SMLF'    | 'IC'     | 'BC034AFCZ00'(!) = ''              | ''             | 'BC034AFCZ00' |'D1510_SMAF-C'| 'DIODE SMD SB34AFC(40V,3A,SCHOTTKY)'       | 'PJT'   | 'SB34AFC'         | 'EP(V1)'     | 'EP(V1)'  | 'IC'  | ''      | ''                | 'S9S-CHRIS'      | 'PJT_SB34AFC.pdf'                     | ''            | ''  | ''         | ''      | '20201125' | ''    
 'SB34AFC'         | 'SMLF'    | 'EMPTY'  | 'BC034AFCZ00'(!) = ''              | ''             | 'BC034AFCZ00' |'D1510_SMAF-C'| 'DIODE SMD SB34AFC(40V,3A,SCHOTTKY)'       | 'PJT'   | 'SB34AFC'         | 'EP(V1)'     | 'EP(V1)'  | 'IC'  | ''      | ''                | 'S9S-CHRIS'      | 'PJT_SB34AFC.pdf'                     | ''            | ''  | ''         | ''      | '20201125' | ''    
 'B520C-13-F'      | 'SMLF'    | 'IC'     | 'BC0B520CZ00'(!) = ''              | ''             | 'BC0B520CZ00' |'D2723_SMCXF'| 'DIODE SMD B520C-13-F(20V,5A,SMC)'         | 'DDS'   | 'B520C-13-F'      | 'EP'         | ''        | 'IC'  | ''      | ''                | 'S6YQ-SIMON'     | 'DDS_B520C-13-F.pdf'                  | ''            | ''  | ''         | ''      | '20201230' | ''    
 'B520C-13-F'      | 'SMLF'    | 'EMPTY'  | 'BC0B520CZ00'(!) = ''              | ''             | 'BC0B520CZ00' |'D2723_SMCXF'| 'DIODE SMD B520C-13-F(20V,5A,SMC)'         | 'DDS'   | 'B520C-13-F'      | 'EP'         | ''        | 'IC'  | ''      | ''                | 'S6YQ-SIMON'     | 'DDS_B520C-13-F.pdf'                  | ''            | ''  | ''         | ''      | '20201230' | ''    
 'RB751VM-40TE-17' | 'SMLF'    | 'IC'     | 'BCRB751VZ01'(!) = ''              | ''             | 'BCRB751VZ01' |'SOD323_1-7X1-25XA'| 'DIODE SMD RB751VM-40TE-17(40V,30MA)'      | 'ROH'   | 'RB751VM-40TE-17' | 'EP(V1)'     | 'EP(V1)'  | 'IC'  | ''      | ''                | 'T6G-JAY'        | 'ROH_RB751VM-40TE-17.pdf'             | ''            | ''  | ''         | ''      | '20210607' | ''    
 'RB751VM-40TE-17' | 'SMLF'    | 'EMPTY'  | 'BCRB751VZ01'(!) = ''              | ''             | 'BCRB751VZ01' |'SOD323_1-7X1-25XA'| 'DIODE SMD RB751VM-40TE-17(40V,30MA)'      | 'ROH'   | 'RB751VM-40TE-17' | 'EP(V1)'     | 'EP(V1)'  | 'IC'  | ''      | ''                | 'T6G-JAY'        | 'ROH_RB751VM-40TE-17.pdf'             | ''            | ''  | ''         | ''      | '20210607' | ''    
 'RSX101VYM30FHTR' | 'SMLF'    | 'IC'     | 'BC1VYM30Z00'(!) = ''              | ''             | 'BC1VYM30Z00' |'SOD323_2X1-4'| 'DIODE SMD RSX101VYM30FH(30V,1A)SCHOTTKY'  | 'ROH'   | 'RSX101VYM30FHTR' | 'EP(V1)'     | ''        | 'IC'  | ''      | ''                | 'F08-FENTUS'     | 'ROH_RSX101VYM30FHTR.pdf'             | ''            | ''  | ''         | ''      | '20210721' | ''    
 'RSX101VYM30FHTR' | 'SMLF'    | 'EMPTY'  | 'BC1VYM30Z00'(!) = ''              | ''             | 'BC1VYM30Z00' |'SOD323_2X1-4'| 'DIODE SMD RSX101VYM30FH(30V,1A)SCHOTTKY'  | 'ROH'   | 'RSX101VYM30FHTR' | 'EP(V1)'     | ''        | 'IC'  | ''      | ''                | 'F08-FENTUS'     | 'ROH_RSX101VYM30FHTR.pdf'             | ''            | ''  | ''         | ''      | '20210721' | ''    
 'CUS10S30'        | 'SMLF'    | 'IC'     | 'BCS10S30Z00'(!) = ''              | ''             | 'BCS10S30Z00' |'SOD323_1-7X1-25XB'| 'DIODE SMD SCHOTTKY  CUS10S30(30V,1A)'     | 'TOS'   | 'CUS10S30'        | 'EP(V1)'     | ''        | 'IC'  | ''      | ''                | 'A7M-ANDY'       | 'TOS_CUS10S30.pdf'                    | ''            | ''  | ''         | ''      | '20210805' | ''    
 'CUS10S30'        | 'SMLF'    | 'EMPTY'  | 'BCS10S30Z00'(!) = ''              | ''             | 'BCS10S30Z00' |'SOD323_1-7X1-25XB'| 'DIODE SMD SCHOTTKY  CUS10S30(30V,1A)'     | 'TOS'   | 'CUS10S30'        | 'EP(V1)'     | ''        | 'IC'  | ''      | ''                | 'A7M-ANDY'       | 'TOS_CUS10S30.pdf'                    | ''            | ''  | ''         | ''      | '20210805' | ''    
 'CUS10F30'        | 'SMLF'    | 'IC'     | 'BC0CUS10000'(!) = 'End of Design' | 'Comp-Approve' | 'BC0CUS10000' |'SOD323_1-7X1-25XB'| 'DIODE SMD SCHOTTKY  CUS10F30(30V,1A)'     | 'TOS'   | 'CUS10F30'        | 'EP(V1)'     | 'EP(V1)'  | 'IC'  | ''      | ''                | 'A7M-ANDY'       | 'TOS_CUS10F30.pdf'                    | ''            | ''  | ''         | ''      | '20210827' | ''    
 'CUS10F30'        | 'SMLF'    | 'EMPTY'  | 'BC0CUS10000'(!) = 'End of Design' | 'Comp-Approve' | 'BC0CUS10000' |'SOD323_1-7X1-25XB'| 'DIODE SMD SCHOTTKY  CUS10F30(30V,1A)'     | 'TOS'   | 'CUS10F30'        | 'EP(V1)'     | 'EP(V1)'  | 'IC'  | ''      | ''                | 'A7M-ANDY'       | 'TOS_CUS10F30.pdf'                    | ''            | ''  | ''         | ''      | '20210827' | ''    
 'PMEG4030ER'      | 'SMLF'    | 'IC'     | 'BC4030ERZ00'(!) = ''              | ''             | 'BC4030ERZ00' |'SOD123W_1-7X2-6XA'| 'DIODE PMEG4030ER(40V,3A)SOD123W AEC'      | 'NXP'   | 'PMEG4030ER'      | 'EP(V1)'     | 'EP(V1)'  | 'IC'  | ''      | ''                | 'S8Z-JACK'       | 'NXP_PMEG4030ER.pdf'                  | ''            | ''  | ''         | ''      | '20210930' | ''    
 'PMEG4030ER'      | 'SMLF'    | 'EMPTY'  | 'BC4030ERZ00'(!) = ''              | ''             | 'BC4030ERZ00' |'SOD123W_1-7X2-6XA'| 'DIODE PMEG4030ER(40V,3A)SOD123W AEC'      | 'NXP'   | 'PMEG4030ER'      | 'EP(V1)'     | 'EP(V1)'  | 'IC'  | ''      | ''                | 'S8Z-JACK'       | 'NXP_PMEG4030ER.pdf'                  | ''            | ''  | ''         | ''      | '20210930' | ''    
 'PMEG4005AEA'     | 'SMLF'    | 'IC'     | 'BC4005AEZ00'(!) = ''              | ''             | 'BC4005AEZ00' |'SOD323F_H44'| 'DIODE SMD PMEG4005AEA(40V,0.5A,SOD323)'   | 'NXP'   | 'PMEG4005AEA'     | 'EP(V1)'     | 'EP(V1)'  | 'IC'  | ''      | ''                | 'F0EG-RAY'       | 'NXP_PMEG4005AEA.pdf'                 | ''            | ''  | ''         | ''      | '20220314' | ''    
 'PMEG4005AEA'     | 'SMLF'    | 'EMPTY'  | 'BC4005AEZ00'(!) = ''              | ''             | 'BC4005AEZ00' |'SOD323F_H44'| 'DIODE SMD PMEG4005AEA(40V,0.5A,SOD323)'   | 'NXP'   | 'PMEG4005AEA'     | 'EP(V1)'     | 'EP(V1)'  | 'IC'  | ''      | ''                | 'F0EG-RAY'       | 'NXP_PMEG4005AEA.pdf'                 | ''            | ''  | ''         | ''      | '20220314' | ''    
 'SS0520'          | 'SMLF'    | 'IC'     | 'BCSS0520Z00'(!) = ''              | ''             | 'BCSS0520Z00' |'SOD123XD'| 'DIODE SMD SS0520(40V, 0.5A)SOD-123'       | 'PJT'   | 'SS0520'          | 'EP(V1)'     | 'EP(V1)'  | 'IC'  | ''      | ''                | 'F06D-DUNCAN'    | 'PJT_SS0520-SS0540.pdf'               | ''            | ''  | ''         | ''      | '20220325' | ''    
 'SS0520'          | 'SMLF'    | 'EMPTY'  | 'BCSS0520Z00'(!) = ''              | ''             | 'BCSS0520Z00' |'SOD123XD'| 'DIODE SMD SS0520(40V, 0.5A)SOD-123'       | 'PJT'   | 'SS0520'          | 'EP(V1)'     | 'EP(V1)'  | 'IC'  | ''      | ''                | 'F06D-DUNCAN'    | 'PJT_SS0520-SS0540.pdf'               | ''            | ''  | ''         | ''      | '20220325' | ''    
 'NSR0130P2T5G'    | 'SMLF'    | 'IC'     | 'BC000130Z05'(!) = ''              | ''             | 'BC000130Z05' |'SOD923'| 'DIODE SMD NSR0130P2T5G(30V,0.1A,SOD-923)' | 'ONS'   | 'NSR0130P2T5G'    | 'EP(V1)'     | 'EP(V1)'  | 'IC'  | ''      | ''                | 'MF6-YAN'        | 'ONS_NSR0130P2T5G.pdf'                | ''            | ''  | ''         | ''      | '20220610' | ''    
 'NSR0130P2T5G'    | 'SMLF'    | 'EMPTY'  | 'BC000130Z05'(!) = ''              | ''             | 'BC000130Z05' |'SOD923'| 'DIODE SMD NSR0130P2T5G(30V,0.1A,SOD-923)' | 'ONS'   | 'NSR0130P2T5G'    | 'EP(V1)'     | 'EP(V1)'  | 'IC'  | ''      | ''                | 'MF6-YAN'        | 'ONS_NSR0130P2T5G.pdf'                | ''            | ''  | ''         | ''      | '20220610' | ''    
 'SSA34-M3/61T'    | 'SMLF'    | 'IC'     | 'BC0SSA34Z00'(!) = ''              | ''             | 'BC0SSA34Z00' |'D1710_SMAXB'| 'DIODE SMD SSA34-M3/61T(40V,3A)'           | 'SIL'   | 'SSA34-M3/61T'    | 'EP(V1)'     | ''        | 'IC'  | ''      | 'SSA34-M361T.msg' | 'F0T-PETER'      | 'SIL_SSA34-M361T.pdf'                 | ''            | ''  | ''         | ''      | '20221209' | ''    
 'SSA34-M3/61T'    | 'SMLF'    | 'EMPTY'  | 'BC0SSA34Z00'(!) = ''              | ''             | 'BC0SSA34Z00' |'D1710_SMAXB'| 'DIODE SMD SSA34-M3/61T(40V,3A)'           | 'SIL'   | 'SSA34-M3/61T'    | 'EP(V1)'     | ''        | 'IC'  | ''      | 'SSA34-M361T.msg' | 'F0T-PETER'      | 'SIL_SSA34-M361T.pdf'                 | ''            | ''  | ''         | ''      | '20221209' | ''    
 'BAS70WS'         | 'SMLF'    | 'IC'     | 'BCAS70WSZ00'(!) = ''              | ''             | 'BCAS70WSZ00' |'SOD323_1-85X1-25'| 'DIODE SCHOTTKY BAS70WS(70V,4A)'           | 'PJT'   | 'BAS70WS'         | 'EP(V1)'     | 'EP(V1)'  | 'IC'  | ''      | 'BAS70WS.msg'     | 'S7M-JAY'        | 'PJT_BAS70WS.pdf'                     | ''            | ''  | ''         | ''      | '20230109' | ''    
 'BAS70WS'         | 'SMLF'    | 'EMPTY'  | 'BCAS70WSZ00'(!) = ''              | ''             | 'BCAS70WSZ00' |'SOD323_1-85X1-25'| 'DIODE SCHOTTKY BAS70WS(70V,4A)'           | 'PJT'   | 'BAS70WS'         | 'EP(V1)'     | 'EP(V1)'  | 'IC'  | ''      | 'BAS70WS.msg'     | 'S7M-JAY'        | 'PJT_BAS70WS.pdf'                     | ''            | ''  | ''         | ''      | '20230109' | ''    
 'SD101BWS-TP'     | 'SMLF'    | 'IC'     | 'BC101BWSZ00'(!) = ''              | ''             | 'BC101BWSZ00' |'SOD323XJ'| 'DIODE SMD SD101BWS-TP(50V,400MW)'         | 'MCE'   | 'SD101BWS-TP'     | 'EU(V1)'     | 'EU(V1)'  | 'IC'  | ''      | ''                | 'T2HV-EASON'     | 'MCE_SD101BWS-TP.pdf'                 | ''            | ''  | ''         | ''      | '20230110' | ''    
 'SD101BWS-TP'     | 'SMLF'    | 'EMPTY'  | 'BC101BWSZ00'(!) = ''              | ''             | 'BC101BWSZ00' |'SOD323XJ'| 'DIODE SMD SD101BWS-TP(50V,400MW)'         | 'MCE'   | 'SD101BWS-TP'     | 'EU(V1)'     | 'EU(V1)'  | 'IC'  | ''      | ''                | 'T2HV-EASON'     | 'MCE_SD101BWS-TP.pdf'                 | ''            | ''  | ''         | ''      | '20230110' | ''    
 'SS1030'          | 'SMLF'    | 'IC'     | 'BC001030Z02'(!) = ''              | ''               | 'BC001030Z02' |'SOD123XD'| 'DIODE SMD SS1030(30V,1A)SOD-123'          | 'PJT'   | 'SS1030'          | 'EP(V1)'     | 'EP(V1)'  | 'IC'  | ''      | ''                | 'S8G-KEN'        | 'PJT_SS1030.pdf'                      | ''            | ''  | ''         | ''      | '20230310' | ''    
 'SS1030'          | 'SMLF'    | 'EMPTY'  | 'BC001030Z02'(!) = ''              | ''               | 'BC001030Z02' |'SOD123XD'| 'DIODE SMD SS1030(30V,1A)SOD-123'          | 'PJT'   | 'SS1030'          | 'EP(V1)'     | 'EP(V1)'  | 'IC'  | ''      | ''                | 'S8G-KEN'        | 'PJT_SS1030.pdf'                      | ''            | ''  | ''         | ''      | '20230310' | ''    

END_PART

END.

